(kicad_pcb
	(version 20260206)
	(generator "pcbnew")
	(generator_version "10.0")
	(general
		(thickness 1.6)
		(legacy_teardrops no)
	)
	(paper "A4")
	(title_block
		(title "Bryce Canyon_SCC_16316-1_OCP.brd")
		(comment 1 "Bryce Canyon / footprints 1167-1173 of 1561")
	)
	(layers
		(0 "F.Cu" signal "TOP")
		(4 "In1.Cu" signal "L2GND")
		(6 "In2.Cu" signal "L3")
		(8 "In3.Cu" signal "L4VCC")
		(10 "In4.Cu" signal "L5VCC")
		(12 "In5.Cu" signal "L6")
		(14 "In6.Cu" signal "L7GND")
		(2 "B.Cu" signal "BOTTOM")
		(9 "F.Adhes" user "F.Adhesive")
		(11 "B.Adhes" user "B.Adhesive")
		(13 "F.Paste" user "Package Geometry/Pastemask Top")
		(15 "B.Paste" user "Package Geometry/Pastemask Bottom")
		(5 "F.SilkS" user "Ref Des/Silkscreen Top")
		(7 "B.SilkS" user "Ref Des/Silkscreen Bottom")
		(1 "F.Mask" user "Board Geometry/Soldermask Top")
		(3 "B.Mask" user "Board Geometry/Soldermask Bottom")
		(17 "Dwgs.User" user "User.Drawings")
		(19 "Cmts.User" user "User.Comments")
		(21 "Eco1.User" user "User.Eco1")
		(23 "Eco2.User" user "User.Eco2")
		(25 "Edge.Cuts" user "Board Geometry/Outline")
		(27 "Margin" user)
		(31 "F.CrtYd" user "Package Geometry/Place Bound Top")
		(29 "B.CrtYd" user "Package Geometry/Place Bound Bottom")
		(35 "F.Fab" user "Ref Des/Assembly Top")
		(33 "B.Fab" user "Ref Des/Assembly Bottom")
	)
	(footprint ""
		(layer "B.Cu")
		(at 114.6302 -87.0204 180)
		(property "Reference" "R141"
			(at 0 0 0)
			(layer "B.SilkS")
			(hide yes)
			(effects
				(font
					(size 1.27 1.27)
				)
				(justify mirror)
			)
		)
		(property "Value" "4K7R2F-GP"
			(at -0.064008 -3.993896 180)
			(unlocked yes)
			(layer "B.Fab")
			(hide yes)
			(effects
				(font
					(size 1.016 1.016)
					(thickness 0.1524)
				)
				(justify mirror)
			)
		)
		(property "Device Type" "R402H16"
			(at -0.064008 -5.517896 180)
			(unlocked yes)
			(layer "B.Fab")
			(hide yes)
			(effects
				(font
					(size 1.016 1.016)
					(thickness 0.1524)
				)
				(justify mirror)
			)
		)
		(duplicate_pad_numbers_are_jumpers no)
		(fp_line
			(start 0.508 -0.9398)
			(end 0.508 0.9398)
			(stroke
				(width 0.1524)
				(type default)
			)
			(layer "B.SilkS")
		)
		(fp_line
			(start -0.508 -0.9398)
			(end 0.508 -0.9398)
			(stroke
				(width 0.1524)
				(type default)
			)
			(layer "B.SilkS")
		)
		(fp_rect
			(start 0.508 0.9398)
			(end -0.508 -0.9398)
			(stroke
				(width 0)
				(type default)
			)
			(fill no)
			(layer "B.CrtYd")
		)
		(fp_rect
			(start 0.508 0.9398)
			(end -0.508 -0.9398)
			(stroke
				(width 0)
				(type default)
			)
			(fill no)
			(layer "B.Fab")
		)
		(pad "1" smd custom
			(at 0 -0.4445)
			(size 0.1397 0.1397)
			(layers "B.Cu" "B.Mask" "B.Paste")
			(net "EXP_XM_ADDR_15")
			(options
				(clearance outline)
				(anchor circle)
			)
			(primitives
				(gr_poly
					(pts
						(arc
							(start -0.1778 0.2794)
							(mid -0.249642 0.249642)
							(end -0.2794 0.1778)
						)
						(arc
							(start -0.2794 -0.1778)
							(mid -0.249642 -0.249642)
							(end -0.1778 -0.2794)
						)
						(arc
							(start 0.1778 -0.2794)
							(mid 0.249642 -0.249642)
							(end 0.2794 -0.1778)
						)
						(arc
							(start 0.2794 0.1778)
							(mid 0.249642 0.249642)
							(end 0.1778 0.2794)
						)
					)
					(width 0)
					(fill yes)
				)
			)
		)
		(pad "2" smd custom
			(at 0 0.4445)
			(size 0.1397 0.1397)
			(layers "B.Cu" "B.Mask" "B.Paste")
			(net "GND")
			(options
				(clearance outline)
				(anchor circle)
			)
			(primitives
				(gr_poly
					(pts
						(arc
							(start -0.1778 0.2794)
							(mid -0.249642 0.249642)
							(end -0.2794 0.1778)
						)
						(arc
							(start -0.2794 -0.1778)
							(mid -0.249642 -0.249642)
							(end -0.1778 -0.2794)
						)
						(arc
							(start 0.1778 -0.2794)
							(mid 0.249642 -0.249642)
							(end 0.2794 -0.1778)
						)
						(arc
							(start 0.2794 0.1778)
							(mid 0.249642 0.249642)
							(end 0.1778 0.2794)
						)
					)
					(width 0)
					(fill yes)
				)
			)
		)
	)
	(footprint ""
		(layer "B.Cu")
		(at 116.713 -68.6562)
		(property "Reference" "C179"
			(at 0 0 0)
			(layer "B.SilkS")
			(hide yes)
			(effects
				(font
					(size 1.27 1.27)
				)
				(justify mirror)
			)
		)
		(property "Value" "SCD1U6D3V1KX-GP"
			(at 2.8321 -1.7399 0)
			(unlocked yes)
			(layer "B.Fab")
			(hide yes)
			(effects
				(font
					(size 1.016 1.016)
					(thickness 0.1524)
				)
				(justify mirror)
			)
		)
		(property "Device Type" "C0201H13"
			(at 2.8321 -3.2639 0)
			(unlocked yes)
			(layer "B.Fab")
			(hide yes)
			(effects
				(font
					(size 1.016 1.016)
					(thickness 0.1524)
				)
				(justify mirror)
			)
		)
		(duplicate_pad_numbers_are_jumpers no)
		(fp_rect
			(start 0.2794 0.6477)
			(end -0.2794 -0.6477)
			(stroke
				(width 0)
				(type default)
			)
			(fill no)
			(layer "B.CrtYd")
		)
		(fp_rect
			(start 0.2794 0.6477)
			(end -0.2794 -0.6477)
			(stroke
				(width 0)
				(type default)
			)
			(fill no)
			(layer "B.Fab")
		)
		(pad "1" smd custom
			(at 0 -0.2794 180)
			(size 0.0762 0.0762)
			(layers "B.Cu" "B.Mask" "B.Paste")
			(net "P0V9")
			(options
				(clearance outline)
				(anchor circle)
			)
			(primitives
				(gr_poly
					(pts
						(arc
							(start 0.1524 0.127)
							(mid 0.137521 0.162921)
							(end 0.1016 0.1778)
						)
						(arc
							(start -0.1016 0.1778)
							(mid -0.137521 0.162921)
							(end -0.1524 0.127)
						)
						(arc
							(start -0.1524 -0.127)
							(mid -0.137521 -0.162921)
							(end -0.1016 -0.1778)
						)
						(arc
							(start 0.1016 -0.1778)
							(mid 0.137521 -0.162921)
							(end 0.1524 -0.127)
						)
					)
					(width 0)
					(fill yes)
				)
			)
		)
		(pad "2" smd custom
			(at 0 0.2794 180)
			(size 0.0762 0.0762)
			(layers "B.Cu" "B.Mask" "B.Paste")
			(net "GND")
			(options
				(clearance outline)
				(anchor circle)
			)
			(primitives
				(gr_poly
					(pts
						(arc
							(start 0.1524 0.127)
							(mid 0.137521 0.162921)
							(end 0.1016 0.1778)
						)
						(arc
							(start -0.1016 0.1778)
							(mid -0.137521 0.162921)
							(end -0.1524 0.127)
						)
						(arc
							(start -0.1524 -0.127)
							(mid -0.137521 -0.162921)
							(end -0.1016 -0.1778)
						)
						(arc
							(start 0.1016 -0.1778)
							(mid 0.137521 -0.162921)
							(end 0.1524 -0.127)
						)
					)
					(width 0)
					(fill yes)
				)
			)
		)
	)
	(footprint ""
		(layer "B.Cu")
		(at 115.316 -68.6562)
		(property "Reference" "C168"
			(at 0 0 0)
			(layer "B.SilkS")
			(hide yes)
			(effects
				(font
					(size 1.27 1.27)
				)
				(justify mirror)
			)
		)
		(property "Value" "SCD1U6D3V1KX-GP"
			(at 2.8321 -1.7399 0)
			(unlocked yes)
			(layer "B.Fab")
			(hide yes)
			(effects
				(font
					(size 1.016 1.016)
					(thickness 0.1524)
				)
				(justify mirror)
			)
		)
		(property "Device Type" "C0201H13"
			(at 2.8321 -3.2639 0)
			(unlocked yes)
			(layer "B.Fab")
			(hide yes)
			(effects
				(font
					(size 1.016 1.016)
					(thickness 0.1524)
				)
				(justify mirror)
			)
		)
		(duplicate_pad_numbers_are_jumpers no)
		(fp_rect
			(start 0.2794 0.6477)
			(end -0.2794 -0.6477)
			(stroke
				(width 0)
				(type default)
			)
			(fill no)
			(layer "B.CrtYd")
		)
		(fp_rect
			(start 0.2794 0.6477)
			(end -0.2794 -0.6477)
			(stroke
				(width 0)
				(type default)
			)
			(fill no)
			(layer "B.Fab")
		)
		(pad "1" smd custom
			(at 0 -0.2794 180)
			(size 0.0762 0.0762)
			(layers "B.Cu" "B.Mask" "B.Paste")
			(net "P0V9")
			(options
				(clearance outline)
				(anchor circle)
			)
			(primitives
				(gr_poly
					(pts
						(arc
							(start 0.1524 0.127)
							(mid 0.137521 0.162921)
							(end 0.1016 0.1778)
						)
						(arc
							(start -0.1016 0.1778)
							(mid -0.137521 0.162921)
							(end -0.1524 0.127)
						)
						(arc
							(start -0.1524 -0.127)
							(mid -0.137521 -0.162921)
							(end -0.1016 -0.1778)
						)
						(arc
							(start 0.1016 -0.1778)
							(mid 0.137521 -0.162921)
							(end 0.1524 -0.127)
						)
					)
					(width 0)
					(fill yes)
				)
			)
		)
		(pad "2" smd custom
			(at 0 0.2794 180)
			(size 0.0762 0.0762)
			(layers "B.Cu" "B.Mask" "B.Paste")
			(net "GND")
			(options
				(clearance outline)
				(anchor circle)
			)
			(primitives
				(gr_poly
					(pts
						(arc
							(start 0.1524 0.127)
							(mid 0.137521 0.162921)
							(end 0.1016 0.1778)
						)
						(arc
							(start -0.1016 0.1778)
							(mid -0.137521 0.162921)
							(end -0.1524 0.127)
						)
						(arc
							(start -0.1524 -0.127)
							(mid -0.137521 -0.162921)
							(end -0.1016 -0.1778)
						)
						(arc
							(start 0.1016 -0.1778)
							(mid 0.137521 -0.162921)
							(end 0.1524 -0.127)
						)
					)
					(width 0)
					(fill yes)
				)
			)
		)
	)
	(footprint ""
		(layer "B.Cu")
		(at 200.5203 -46.4439 -90)
		(property "Reference" "R202"
			(at 0 0 90)
			(layer "B.SilkS")
			(hide yes)
			(effects
				(font
					(size 1.27 1.27)
				)
				(justify mirror)
			)
		)
		(property "Value" "0R2J-2-GP"
			(at -0.064008 -3.993896 270)
			(unlocked yes)
			(layer "B.Fab")
			(hide yes)
			(effects
				(font
					(size 1.016 1.016)
					(thickness 0.1524)
				)
				(justify mirror)
			)
		)
		(property "Device Type" "R402H16"
			(at -0.064008 -5.517896 270)
			(unlocked yes)
			(layer "B.Fab")
			(hide yes)
			(effects
				(font
					(size 1.016 1.016)
					(thickness 0.1524)
				)
				(justify mirror)
			)
		)
		(duplicate_pad_numbers_are_jumpers no)
		(fp_line
			(start -0.508 -0.9398)
			(end 0.508 -0.9398)
			(stroke
				(width 0.1524)
				(type default)
			)
			(layer "B.SilkS")
		)
		(fp_line
			(start 0.508 -0.9398)
			(end 0.508 0.9398)
			(stroke
				(width 0.1524)
				(type default)
			)
			(layer "B.SilkS")
		)
		(fp_rect
			(start 0.508 0.9398)
			(end -0.508 -0.9398)
			(stroke
				(width 0)
				(type default)
			)
			(fill no)
			(layer "B.CrtYd")
		)
		(fp_rect
			(start 0.508 0.9398)
			(end -0.508 -0.9398)
			(stroke
				(width 0)
				(type default)
			)
			(fill no)
			(layer "B.Fab")
		)
		(pad "1" smd custom
			(at 0 -0.4445 90)
			(size 0.1397 0.1397)
			(layers "B.Cu" "B.Mask" "B.Paste")
			(net "IOC_EEPROM_SCL")
			(options
				(clearance outline)
				(anchor circle)
			)
			(primitives
				(gr_poly
					(pts
						(arc
							(start -0.1778 0.2794)
							(mid -0.249642 0.249642)
							(end -0.2794 0.1778)
						)
						(arc
							(start -0.2794 -0.1778)
							(mid -0.249642 -0.249642)
							(end -0.1778 -0.2794)
						)
						(arc
							(start 0.1778 -0.2794)
							(mid 0.249642 -0.249642)
							(end 0.2794 -0.1778)
						)
						(arc
							(start 0.2794 0.1778)
							(mid 0.249642 0.249642)
							(end 0.1778 0.2794)
						)
					)
					(width 0)
					(fill yes)
				)
			)
		)
		(pad "2" smd custom
			(at 0 0.4445 90)
			(size 0.1397 0.1397)
			(layers "B.Cu" "B.Mask" "B.Paste")
			(net "SBL_SCL")
			(options
				(clearance outline)
				(anchor circle)
			)
			(primitives
				(gr_poly
					(pts
						(arc
							(start -0.1778 0.2794)
							(mid -0.249642 0.249642)
							(end -0.2794 0.1778)
						)
						(arc
							(start -0.2794 -0.1778)
							(mid -0.249642 -0.249642)
							(end -0.1778 -0.2794)
						)
						(arc
							(start 0.1778 -0.2794)
							(mid 0.249642 -0.249642)
							(end 0.2794 -0.1778)
						)
						(arc
							(start 0.2794 0.1778)
							(mid 0.249642 0.249642)
							(end 0.1778 0.2794)
						)
					)
					(width 0)
					(fill yes)
				)
			)
		)
	)
	(footprint ""
		(layer "B.Cu")
		(at 144.332706 -117.160294 90)
		(property "Reference" "R539"
			(at 0 0 90)
			(layer "B.SilkS")
			(hide yes)
			(effects
				(font
					(size 1.27 1.27)
				)
				(justify mirror)
			)
		)
		(property "Value" "0R2J-2-GP"
			(at -0.064008 -3.993896 90)
			(unlocked yes)
			(layer "B.Fab")
			(hide yes)
			(effects
				(font
					(size 1.016 1.016)
					(thickness 0.1524)
				)
				(justify mirror)
			)
		)
		(property "Device Type" "R402H16"
			(at -0.064008 -5.517896 90)
			(unlocked yes)
			(layer "B.Fab")
			(hide yes)
			(effects
				(font
					(size 1.016 1.016)
					(thickness 0.1524)
				)
				(justify mirror)
			)
		)
		(duplicate_pad_numbers_are_jumpers no)
		(fp_line
			(start 0.508 -0.9398)
			(end 0.508 0.9398)
			(stroke
				(width 0.1524)
				(type default)
			)
			(layer "B.SilkS")
		)
		(fp_line
			(start -0.508 -0.9398)
			(end 0.508 -0.9398)
			(stroke
				(width 0.1524)
				(type default)
			)
			(layer "B.SilkS")
		)
		(fp_rect
			(start 0.508 0.9398)
			(end -0.508 -0.9398)
			(stroke
				(width 0)
				(type default)
			)
			(fill no)
			(layer "B.CrtYd")
		)
		(fp_rect
			(start 0.508 0.9398)
			(end -0.508 -0.9398)
			(stroke
				(width 0)
				(type default)
			)
			(fill no)
			(layer "B.Fab")
		)
		(pad "1" smd custom
			(at 0 -0.4445 270)
			(size 0.1397 0.1397)
			(layers "B.Cu" "B.Mask" "B.Paste")
			(net "P1V5_C_S")
			(options
				(clearance outline)
				(anchor circle)
			)
			(primitives
				(gr_poly
					(pts
						(arc
							(start -0.1778 0.2794)
							(mid -0.249642 0.249642)
							(end -0.2794 0.1778)
						)
						(arc
							(start -0.2794 -0.1778)
							(mid -0.249642 -0.249642)
							(end -0.1778 -0.2794)
						)
						(arc
							(start 0.1778 -0.2794)
							(mid 0.249642 -0.249642)
							(end 0.2794 -0.1778)
						)
						(arc
							(start 0.2794 0.1778)
							(mid 0.249642 0.249642)
							(end 0.1778 0.2794)
						)
					)
					(width 0)
					(fill yes)
				)
			)
		)
		(pad "2" smd custom
			(at 0 0.4445 270)
			(size 0.1397 0.1397)
			(layers "B.Cu" "B.Mask" "B.Paste")
			(net "P1V8_C_PG")
			(options
				(clearance outline)
				(anchor circle)
			)
			(primitives
				(gr_poly
					(pts
						(arc
							(start -0.1778 0.2794)
							(mid -0.249642 0.249642)
							(end -0.2794 0.1778)
						)
						(arc
							(start -0.2794 -0.1778)
							(mid -0.249642 -0.249642)
							(end -0.1778 -0.2794)
						)
						(arc
							(start 0.1778 -0.2794)
							(mid 0.249642 -0.249642)
							(end 0.2794 -0.1778)
						)
						(arc
							(start 0.2794 0.1778)
							(mid 0.249642 0.249642)
							(end 0.1778 0.2794)
						)
					)
					(width 0)
					(fill yes)
				)
			)
		)
	)
	(footprint ""
		(layer "B.Cu")
		(at 155.327604 -66.866008)
		(property "Reference" "R278"
			(at 0 0 0)
			(layer "B.SilkS")
			(hide yes)
			(effects
				(font
					(size 1.27 1.27)
				)
				(justify mirror)
			)
		)
		(property "Value" "10R2F-L-GP"
			(at -0.064008 -3.993896 0)
			(unlocked yes)
			(layer "B.Fab")
			(hide yes)
			(effects
				(font
					(size 1.016 1.016)
					(thickness 0.1524)
				)
				(justify mirror)
			)
		)
		(property "Device Type" "R402H14"
			(at -0.064008 -5.517896 0)
			(unlocked yes)
			(layer "B.Fab")
			(hide yes)
			(effects
				(font
					(size 1.016 1.016)
					(thickness 0.1524)
				)
				(justify mirror)
			)
		)
		(duplicate_pad_numbers_are_jumpers no)
		(fp_line
			(start -0.508 -0.9398)
			(end 0.508 -0.9398)
			(stroke
				(width 0.1524)
				(type default)
			)
			(layer "B.SilkS")
		)
		(fp_line
			(start 0.508 -0.9398)
			(end 0.508 0.9398)
			(stroke
				(width 0.1524)
				(type default)
			)
			(layer "B.SilkS")
		)
		(fp_rect
			(start 0.508 0.9398)
			(end -0.508 -0.9398)
			(stroke
				(width 0)
				(type default)
			)
			(fill no)
			(layer "B.CrtYd")
		)
		(fp_rect
			(start 0.508 0.9398)
			(end -0.508 -0.9398)
			(stroke
				(width 0)
				(type default)
			)
			(fill no)
			(layer "B.Fab")
		)
		(pad "1" smd custom
			(at 0 -0.4445 180)
			(size 0.1397 0.1397)
			(layers "B.Cu" "B.Mask" "B.Paste")
			(net "P1V8_C")
			(options
				(clearance outline)
				(anchor circle)
			)
			(primitives
				(gr_poly
					(pts
						(arc
							(start -0.1778 0.2794)
							(mid -0.249642 0.249642)
							(end -0.2794 0.1778)
						)
						(arc
							(start -0.2794 -0.1778)
							(mid -0.249642 -0.249642)
							(end -0.1778 -0.2794)
						)
						(arc
							(start 0.1778 -0.2794)
							(mid 0.249642 -0.249642)
							(end 0.2794 -0.1778)
						)
						(arc
							(start 0.2794 0.1778)
							(mid 0.249642 0.249642)
							(end 0.1778 0.2794)
						)
					)
					(width 0)
					(fill yes)
				)
			)
		)
		(pad "2" smd custom
			(at 0 0.4445 180)
			(size 0.1397 0.1397)
			(layers "B.Cu" "B.Mask" "B.Paste")
			(net "SYS_PLL_VDD")
			(options
				(clearance outline)
				(anchor circle)
			)
			(primitives
				(gr_poly
					(pts
						(arc
							(start -0.1778 0.2794)
							(mid -0.249642 0.249642)
							(end -0.2794 0.1778)
						)
						(arc
							(start -0.2794 -0.1778)
							(mid -0.249642 -0.249642)
							(end -0.1778 -0.2794)
						)
						(arc
							(start 0.1778 -0.2794)
							(mid 0.249642 -0.249642)
							(end 0.2794 -0.1778)
						)
						(arc
							(start 0.2794 0.1778)
							(mid 0.249642 0.249642)
							(end 0.1778 0.2794)
						)
					)
					(width 0)
					(fill yes)
				)
			)
		)
	)
	(footprint ""
		(layer "B.Cu")
		(at 187.599066 -38.582346 -90)
		(property "Reference" "R176"
			(at 0 0 90)
			(layer "B.SilkS")
			(hide yes)
			(effects
				(font
					(size 1.27 1.27)
				)
				(justify mirror)
			)
		)
		(property "Value" "10KR2F-2-GP"
			(at -0.064008 -3.993896 270)
			(unlocked yes)
			(layer "B.Fab")
			(hide yes)
			(effects
				(font
					(size 1.016 1.016)
					(thickness 0.1524)
				)
				(justify mirror)
			)
		)
		(property "Device Type" "R402H16"
			(at -0.064008 -5.517896 270)
			(unlocked yes)
			(layer "B.Fab")
			(hide yes)
			(effects
				(font
					(size 1.016 1.016)
					(thickness 0.1524)
				)
				(justify mirror)
			)
		)
		(duplicate_pad_numbers_are_jumpers no)
		(fp_line
			(start -0.508 -0.9398)
			(end 0.508 -0.9398)
			(stroke
				(width 0.1524)
				(type default)
			)
			(layer "B.SilkS")
		)
		(fp_line
			(start 0.508 -0.9398)
			(end 0.508 0.9398)
			(stroke
				(width 0.1524)
				(type default)
			)
			(layer "B.SilkS")
		)
		(fp_rect
			(start 0.508 0.9398)
			(end -0.508 -0.9398)
			(stroke
				(width 0)
				(type default)
			)
			(fill no)
			(layer "B.CrtYd")
		)
		(fp_rect
			(start 0.508 0.9398)
			(end -0.508 -0.9398)
			(stroke
				(width 0)
				(type default)
			)
			(fill no)
			(layer "B.Fab")
		)
		(pad "1" smd custom
			(at 0 -0.4445 90)
			(size 0.1397 0.1397)
			(layers "B.Cu" "B.Mask" "B.Paste")
			(net "GND")
			(options
				(clearance outline)
				(anchor circle)
			)
			(primitives
				(gr_poly
					(pts
						(arc
							(start -0.1778 0.2794)
							(mid -0.249642 0.249642)
							(end -0.2794 0.1778)
						)
						(arc
							(start -0.2794 -0.1778)
							(mid -0.249642 -0.249642)
							(end -0.1778 -0.2794)
						)
						(arc
							(start 0.1778 -0.2794)
							(mid 0.249642 -0.249642)
							(end 0.2794 -0.1778)
						)
						(arc
							(start 0.2794 0.1778)
							(mid 0.249642 0.249642)
							(end 0.1778 0.2794)
						)
					)
					(width 0)
					(fill yes)
				)
			)
		)
		(pad "2" smd custom
			(at 0 0.4445 90)
			(size 0.1397 0.1397)
			(layers "B.Cu" "B.Mask" "B.Paste")
			(net "IOC_CLK_SEL1")
			(options
				(clearance outline)
				(anchor circle)
			)
			(primitives
				(gr_poly
					(pts
						(arc
							(start -0.1778 0.2794)
							(mid -0.249642 0.249642)
							(end -0.2794 0.1778)
						)
						(arc
							(start -0.2794 -0.1778)
							(mid -0.249642 -0.249642)
							(end -0.1778 -0.2794)
						)
						(arc
							(start 0.1778 -0.2794)
							(mid 0.249642 -0.249642)
							(end 0.2794 -0.1778)
						)
						(arc
							(start 0.2794 0.1778)
							(mid 0.249642 0.249642)
							(end 0.1778 0.2794)
						)
					)
					(width 0)
					(fill yes)
				)
			)
		)
	)
)
